(kicad_pcb
	(version 20260206)
	(generator "pcbnew")
	(generator_version "10.0")
	(general
		(thickness 1.6)
		(legacy_teardrops no)
	)
	(paper "A4")
	(title_block
		(title "12092022_DA0F0TMDCD0_F0T_Management_Board_D_brd_V3_OCP.brd")
		(comment 1 "Grand Teton / footprint 124 of 1440 (U5), pads 1-110 of 624")
	)
	(layers
		(0 "F.Cu" signal "TOP")
		(4 "In1.Cu" signal "GND")
		(6 "In2.Cu" signal "IN1")
		(8 "In3.Cu" signal "GND1")
		(10 "In4.Cu" signal "IN2")
		(12 "In5.Cu" signal "VCC")
		(14 "In6.Cu" signal "VCC1")
		(16 "In7.Cu" signal "IN3")
		(18 "In8.Cu" signal "GND2")
		(20 "In9.Cu" signal "IN4")
		(22 "In10.Cu" signal "GND3")
		(2 "B.Cu" signal "BOTTOM")
		(9 "F.Adhes" user "F.Adhesive")
		(11 "B.Adhes" user "B.Adhesive")
		(13 "F.Paste" user "Package Geometry/Pastemask Top")
		(15 "B.Paste" user "Package Geometry/Pastemask Bottom")
		(5 "F.SilkS" user "Ref Des/Silkscreen Top")
		(7 "B.SilkS" user "Ref Des/Silkscreen Bottom")
		(1 "F.Mask" user "Board Geometry/Soldermask Top")
		(3 "B.Mask" user "Board Geometry/Soldermask Bottom")
		(17 "Dwgs.User" user "User.Drawings")
		(19 "Cmts.User" user "User.Comments")
		(21 "Eco1.User" user "User.Eco1")
		(23 "Eco2.User" user "User.Eco2")
		(25 "Edge.Cuts" user "Board Geometry/Outline")
		(27 "Margin" user)
		(31 "F.CrtYd" user "Package Geometry/Place Bound Top")
		(29 "B.CrtYd" user "Package Geometry/Place Bound Bottom")
		(35 "F.Fab" user "Ref Des/Assembly Top")
		(33 "B.Fab" user "Ref Des/Assembly Bottom")
	)
	(footprint ""
		(layer "F.Cu")
		(at 54.894988 -49.37125 180)
		(property "Reference" "U5"
			(at -11.094212 -12.07262 0)
			(unlocked yes)
			(layer "F.SilkS")
			(effects
				(font
					(size 0.7874 0.5842)
					(thickness 0.1524)
				)
				(justify left)
			)
		)
		(property "Value" ""
			(at 0 0 180)
			(layer "F.Fab")
			(effects
				(font
					(size 1.27 1.27)
				)
			)
		)
		(duplicate_pad_numbers_are_jumpers no)
		(pad "A1" smd circle
			(at -9.99998 -9.99998 180)
			(size 0.4064 0.4064)
			(layers "F.Cu" "F.Mask" "F.Paste")
			(net "GND")
		)
		(pad "A2" smd circle
			(at -9.19988 -9.99998 180)
			(size 0.4064 0.4064)
			(layers "F.Cu" "F.Mask" "F.Paste")
			(net "Net_35")
		)
		(pad "A3" smd circle
			(at -8.400034 -9.99998 180)
			(size 0.4064 0.4064)
			(layers "F.Cu" "F.Mask" "F.Paste")
			(net "Net_42")
		)
		(pad "A4" smd circle
			(at -7.599934 -9.99998 180)
			(size 0.4064 0.4064)
			(layers "F.Cu" "F.Mask" "F.Paste")
			(net "USB_HOST_BMC_A_R_DP")
		)
		(pad "A5" smd circle
			(at -6.800088 -9.99998 180)
			(size 0.4064 0.4064)
			(layers "F.Cu" "F.Mask" "F.Paste")
			(net "GND")
		)
		(pad "A6" smd circle
			(at -5.999988 -9.99998 180)
			(size 0.4064 0.4064)
			(layers "F.Cu" "F.Mask" "F.Paste")
			(net "USB_HOST_BMC_B_R_DP")
		)
		(pad "A7" smd circle
			(at -5.199888 -9.99998 180)
			(size 0.4064 0.4064)
			(layers "F.Cu" "F.Mask" "F.Paste")
			(net "RST_PLTRST_N")
		)
		(pad "A8" smd circle
			(at -4.400042 -9.99998 180)
			(size 0.4064 0.4064)
			(layers "F.Cu" "F.Mask" "F.Paste")
			(net "V_BMC_DDC_SDA")
		)
		(pad "A9" smd circle
			(at -3.599942 -9.99998 180)
			(size 0.4064 0.4064)
			(layers "F.Cu" "F.Mask" "F.Paste")
			(net "JTAG_SCM_TMS")
		)
		(pad "A10" smd circle
			(at -2.800096 -9.99998 180)
			(size 0.4064 0.4064)
			(layers "F.Cu" "F.Mask" "F.Paste")
			(net "PD_CLK_125M_PHY_BMC_RGMII")
		)
		(pad "A11" smd circle
			(at -1.999996 -9.99998 180)
			(size 0.4064 0.4064)
			(layers "F.Cu" "F.Mask" "F.Paste")
			(net "SMB_BMC_MM5_R_SCL")
		)
		(pad "A12" smd circle
			(at -1.199896 -9.99998 180)
			(size 0.4064 0.4064)
			(layers "F.Cu" "F.Mask" "F.Paste")
			(net "PWRGD_PSU_AC_PWROK_BMC")
		)
		(pad "A13" smd circle
			(at -0.40005 -9.99998 180)
			(size 0.4064 0.4064)
			(layers "F.Cu" "F.Mask" "F.Paste")
			(net "SMB_BMC_MM10_R_SDA")
		)
		(pad "A14" smd circle
			(at 0.40005 -9.99998 180)
			(size 0.4064 0.4064)
			(layers "F.Cu" "F.Mask" "F.Paste")
			(net "SMB_BMC_MM9_R_SDA")
		)
		(pad "A15" smd circle
			(at 1.199896 -9.99998 180)
			(size 0.4064 0.4064)
			(layers "F.Cu" "F.Mask" "F.Paste")
			(net "IRQ_PCH_SCI_WHEA_R_N")
		)
		(pad "A16" smd circle
			(at 1.999996 -9.99998 180)
			(size 0.4064 0.4064)
			(layers "F.Cu" "F.Mask" "F.Paste")
			(net "JTAG_1_BMC_TDI_R")
		)
		(pad "A17" smd circle
			(at 2.800096 -9.99998 180)
			(size 0.4064 0.4064)
			(layers "F.Cu" "F.Mask" "F.Paste")
			(net "SGPIO_BMC_M1_DI")
		)
		(pad "A18" smd circle
			(at 3.599942 -9.99998 180)
			(size 0.4064 0.4064)
			(layers "F.Cu" "F.Mask" "F.Paste")
			(net "SGPIO_BMC_M1_CLK")
		)
		(pad "A19" smd circle
			(at 4.400042 -9.99998 180)
			(size 0.4064 0.4064)
			(layers "F.Cu" "F.Mask" "F.Paste")
			(net "SMB_BMC_MM3_R_SDA")
		)
		(pad "A20" smd circle
			(at 5.199888 -9.99998 180)
			(size 0.4064 0.4064)
			(layers "F.Cu" "F.Mask" "F.Paste")
			(net "SMB_BMC_MM1_R_SDA")
		)
		(pad "A21" smd circle
			(at 5.999988 -9.99998 180)
			(size 0.4064 0.4064)
			(layers "F.Cu" "F.Mask" "F.Paste")
			(net "BMC_EMMC_DT6")
		)
		(pad "A22" smd circle
			(at 6.800088 -9.99998 180)
			(size 0.4064 0.4064)
			(layers "F.Cu" "F.Mask" "F.Paste")
			(net "BMC_EMMC_DT5")
		)
		(pad "A23" smd circle
			(at 7.599934 -9.99998 180)
			(size 0.4064 0.4064)
			(layers "F.Cu" "F.Mask" "F.Paste")
			(net "BMC_EMMC_WP_N")
		)
		(pad "A24" smd circle
			(at 8.400034 -9.99998 180)
			(size 0.4064 0.4064)
			(layers "F.Cu" "F.Mask" "F.Paste")
			(net "BMC_EMMC_CD_N")
		)
		(pad "A25" smd circle
			(at 9.19988 -9.99998 180)
			(size 0.4064 0.4064)
			(layers "F.Cu" "F.Mask" "F.Paste")
			(net "BMC_EMMC_DT3")
		)
		(pad "A26" smd circle
			(at 9.99998 -9.99998 180)
			(size 0.4064 0.4064)
			(layers "F.Cu" "F.Mask" "F.Paste")
			(net "GND")
		)
		(pad "AA1" smd circle
			(at -9.99998 5.999988 180)
			(size 0.4064 0.4064)
			(layers "F.Cu" "F.Mask" "F.Paste")
			(net "GND")
		)
		(pad "AA2" smd circle
			(at -9.19988 5.999988 180)
			(size 0.4064 0.4064)
			(layers "F.Cu" "F.Mask" "F.Paste")
			(net "NC_DP_BMC_TX1_N")
		)
		(pad "AA3" smd circle
			(at -8.400034 5.999988 180)
			(size 0.4064 0.4064)
			(layers "F.Cu" "F.Mask" "F.Paste")
			(net "GND")
		)
		(pad "AA4" smd circle
			(at -7.599934 5.999988 180)
			(size 0.4064 0.4064)
			(layers "F.Cu" "F.Mask" "F.Paste")
			(net "Net_67")
		)
		(pad "AA5" smd circle
			(at -6.800088 5.999988 180)
			(size 0.4064 0.4064)
			(layers "F.Cu" "F.Mask" "F.Paste")
			(net "Net_65")
		)
		(pad "AA6" smd circle
			(at -5.999988 5.999988 180)
			(size 0.4064 0.4064)
			(layers "F.Cu" "F.Mask" "F.Paste")
			(net "GND")
		)
		(pad "AA7" smd circle
			(at -5.199888 5.999988 180)
			(size 0.4064 0.4064)
			(layers "F.Cu" "F.Mask" "F.Paste")
			(net "GND")
		)
		(pad "AA8" smd circle
			(at -4.400042 5.999988 180)
			(size 0.4064 0.4064)
			(layers "F.Cu" "F.Mask" "F.Paste")
			(net "GND")
		)
		(pad "AA9" smd circle
			(at -3.599942 5.999988 180)
			(size 0.4064 0.4064)
			(layers "F.Cu" "F.Mask" "F.Paste")
			(net "PWRGD_DSW_PWROK_R1")
		)
		(pad "AA10" smd circle
			(at -2.800096 5.999988 180)
			(size 0.4064 0.4064)
			(layers "F.Cu" "F.Mask" "F.Paste")
			(net "GND")
		)
		(pad "AA11" smd circle
			(at -1.999996 5.999988 180)
			(size 0.4064 0.4064)
			(layers "F.Cu" "F.Mask" "F.Paste")
			(net "SPI_BMC_TPM_MISO_R1")
		)
		(pad "AA12" smd circle
			(at -1.199896 5.999988 180)
			(size 0.4064 0.4064)
			(layers "F.Cu" "F.Mask" "F.Paste")
			(net "BMC_EMMC_RST_R_N")
		)
		(pad "AA13" smd circle
			(at -0.40005 5.999988 180)
			(size 0.4064 0.4064)
			(layers "F.Cu" "F.Mask" "F.Paste")
			(net "SPI_BMC_BOOT_CS1_R1_N")
		)
		(pad "AA14" smd circle
			(at 0.40005 5.999988 180)
			(size 0.4064 0.4064)
			(layers "F.Cu" "F.Mask" "F.Paste")
			(net "GND")
		)
		(pad "AA15" smd circle
			(at 1.199896 5.999988 180)
			(size 0.4064 0.4064)
			(layers "F.Cu" "F.Mask" "F.Paste")
			(net "GND")
		)
		(pad "AA16" smd circle
			(at 1.999996 5.999988 180)
			(size 0.4064 0.4064)
			(layers "F.Cu" "F.Mask" "F.Paste")
			(net "FM_BMC_EN_DET_R")
		)
		(pad "AA17" smd circle
			(at 2.800096 5.999988 180)
			(size 0.4064 0.4064)
			(layers "F.Cu" "F.Mask" "F.Paste")
			(net "SMB_BMC_ALERT10_R_N")
		)
		(pad "AA18" smd circle
			(at 3.599942 5.999988 180)
			(size 0.4064 0.4064)
			(layers "F.Cu" "F.Mask" "F.Paste")
			(net "PVCCIO_PECI_BMC")
		)
		(pad "AA19" smd circle
			(at 4.400042 5.999988 180)
			(size 0.4064 0.4064)
			(layers "F.Cu" "F.Mask" "F.Paste")
			(net "GND")
		)
		(pad "AA20" smd circle
			(at 5.199888 5.999988 180)
			(size 0.4064 0.4064)
			(layers "F.Cu" "F.Mask" "F.Paste")
			(net "GND")
		)
		(pad "AA21" smd circle
			(at 5.999988 5.999988 180)
			(size 0.4064 0.4064)
			(layers "F.Cu" "F.Mask" "F.Paste")
			(net "A_BMC_ADCAV33")
		)
		(pad "AA22" smd circle
			(at 6.800088 5.999988 180)
			(size 0.4064 0.4064)
			(layers "F.Cu" "F.Mask" "F.Paste")
			(net "GND")
		)
		(pad "AA23" smd circle
			(at 7.599934 5.999988 180)
			(size 0.4064 0.4064)
			(layers "F.Cu" "F.Mask" "F.Paste")
			(net "ID_RST_BTN_BMC_R_N")
		)
		(pad "AA24" smd circle
			(at 8.400034 5.999988 180)
			(size 0.4064 0.4064)
			(layers "F.Cu" "F.Mask" "F.Paste")
			(net "RST_BMC_RSTBTN_OUT_R_N")
		)
		(pad "AA25" smd circle
			(at 9.19988 5.999988 180)
			(size 0.4064 0.4064)
			(layers "F.Cu" "F.Mask" "F.Paste")
			(net "IRQ_PCH_TPM_SPI_N")
		)
		(pad "AA26" smd circle
			(at 9.99998 5.999988 180)
			(size 0.4064 0.4064)
			(layers "F.Cu" "F.Mask" "F.Paste")
			(net "FM_SOL_UART_CH_SEL_R1")
		)
		(pad "AB1" smd circle
			(at -9.99998 6.800088 180)
			(size 0.4064 0.4064)
			(layers "F.Cu" "F.Mask" "F.Paste")
			(net "NC_DP_BMC_TX0_N")
		)
		(pad "AB2" smd circle
			(at -9.19988 6.800088 180)
			(size 0.4064 0.4064)
			(layers "F.Cu" "F.Mask" "F.Paste")
			(net "NC_DP_BMC_TX1_P")
		)
		(pad "AB3" smd circle
			(at -8.400034 6.800088 180)
			(size 0.4064 0.4064)
			(layers "F.Cu" "F.Mask" "F.Paste")
			(net "NC_DP_BMC_AUX_N")
		)
		(pad "AB4" smd circle
			(at -7.599934 6.800088 180)
			(size 0.4064 0.4064)
			(layers "F.Cu" "F.Mask" "F.Paste")
			(net "Net_68")
		)
		(pad "AB5" smd circle
			(at -6.800088 6.800088 180)
			(size 0.4064 0.4064)
			(layers "F.Cu" "F.Mask" "F.Paste")
			(net "Net_63")
		)
		(pad "AB6" smd circle
			(at -5.999988 6.800088 180)
			(size 0.4064 0.4064)
			(layers "F.Cu" "F.Mask" "F.Paste")
			(net "Net_61")
		)
		(pad "AB7" smd circle
			(at -5.199888 6.800088 180)
			(size 0.4064 0.4064)
			(layers "F.Cu" "F.Mask" "F.Paste")
			(net "ESPI_LPC_D0_IO0")
		)
		(pad "AB8" smd circle
			(at -4.400042 6.800088 180)
			(size 0.4064 0.4064)
			(layers "F.Cu" "F.Mask" "F.Paste")
			(net "ESPI_LPC_D1_IO1")
		)
		(pad "AB9" smd circle
			(at -3.599942 6.800088 180)
			(size 0.4064 0.4064)
			(layers "F.Cu" "F.Mask" "F.Paste")
			(net "SPI_BMC_BIOS_ROM_MOSI")
		)
		(pad "AB10" smd circle
			(at -2.800096 6.800088 180)
			(size 0.4064 0.4064)
			(layers "F.Cu" "F.Mask" "F.Paste")
			(net "SPI_BMC_BIOS_ROM_IO3")
		)
		(pad "AB11" smd circle
			(at -1.999996 6.800088 180)
			(size 0.4064 0.4064)
			(layers "F.Cu" "F.Mask" "F.Paste")
			(net "SPI_BMC_TPM_CLK_R1")
		)
		(pad "AB12" smd circle
			(at -1.199896 6.800088 180)
			(size 0.4064 0.4064)
			(layers "F.Cu" "F.Mask" "F.Paste")
			(net "PU_FWSPIWP_N_R")
		)
		(pad "AB13" smd circle
			(at -0.40005 6.800088 180)
			(size 0.4064 0.4064)
			(layers "F.Cu" "F.Mask" "F.Paste")
			(net "SPI_BMC_MISO_IO1_R")
		)
		(pad "AB14" smd circle
			(at 0.40005 6.800088 180)
			(size 0.4064 0.4064)
			(layers "F.Cu" "F.Mask" "F.Paste")
			(net "SPI_BMC_BOOT_CS0_R1_N")
		)
		(pad "AB15" smd circle
			(at 1.199896 6.800088 180)
			(size 0.4064 0.4064)
			(layers "F.Cu" "F.Mask" "F.Paste")
			(net "FM_SLPS3_GF_R1_N")
		)
		(pad "AB16" smd circle
			(at 1.999996 6.800088 180)
			(size 0.4064 0.4064)
			(layers "F.Cu" "F.Mask" "F.Paste")
			(net "SMB_BMC_ALERT9_R_N")
		)
		(pad "AB17" smd circle
			(at 2.800096 6.800088 180)
			(size 0.4064 0.4064)
			(layers "F.Cu" "F.Mask" "F.Paste")
			(net "P1V0_SENSOR")
		)
		(pad "AB18" smd circle
			(at 3.599942 6.800088 180)
			(size 0.4064 0.4064)
			(layers "F.Cu" "F.Mask" "F.Paste")
			(net "P1V2_SENSOR")
		)
		(pad "AB19" smd circle
			(at 4.400042 6.800088 180)
			(size 0.4064 0.4064)
			(layers "F.Cu" "F.Mask" "F.Paste")
			(net "PGPPA_BMC_AUX_SENSOR")
		)
		(pad "AB20" smd circle
			(at 5.199888 6.800088 180)
			(size 0.4064 0.4064)
			(layers "F.Cu" "F.Mask" "F.Paste")
			(net "A_BMC_ADCVREFN0")
		)
		(pad "AB21" smd circle
			(at 5.999988 6.800088 180)
			(size 0.4064 0.4064)
			(layers "F.Cu" "F.Mask" "F.Paste")
			(net "FM_INTRUDER_R_N")
		)
		(pad "AB22" smd circle
			(at 6.800088 6.800088 180)
			(size 0.4064 0.4064)
			(layers "F.Cu" "F.Mask" "F.Paste")
			(net "FM_PWR_BTN")
		)
		(pad "AB23" smd circle
			(at 7.599934 6.800088 180)
			(size 0.4064 0.4064)
			(layers "F.Cu" "F.Mask" "F.Paste")
			(net "H_CPU0_MEMTRIP_LVC1_N")
		)
		(pad "AB24" smd circle
			(at 8.400034 6.800088 180)
			(size 0.4064 0.4064)
			(layers "F.Cu" "F.Mask" "F.Paste")
			(net "H_CPU1_MEMTRIP_LVC1_N")
		)
		(pad "AB25" smd circle
			(at 9.19988 6.800088 180)
			(size 0.4064 0.4064)
			(layers "F.Cu" "F.Mask" "F.Paste")
			(net "USB_OC0_REAR_R_N")
		)
		(pad "AB26" smd circle
			(at 9.99998 6.800088 180)
			(size 0.4064 0.4064)
			(layers "F.Cu" "F.Mask" "F.Paste")
			(net "GPU_WP_HW_CTRL_R_N")
		)
		(pad "AC1" smd circle
			(at -9.99998 7.599934 180)
			(size 0.4064 0.4064)
			(layers "F.Cu" "F.Mask" "F.Paste")
			(net "NC_DP_BMC_TX0_P")
		)
		(pad "AC2" smd circle
			(at -9.19988 7.599934 180)
			(size 0.4064 0.4064)
			(layers "F.Cu" "F.Mask" "F.Paste")
			(net "GND")
		)
		(pad "AC3" smd circle
			(at -8.400034 7.599934 180)
			(size 0.4064 0.4064)
			(layers "F.Cu" "F.Mask" "F.Paste")
			(net "NC_DP_BMC_AUX_P")
		)
		(pad "AC4" smd circle
			(at -7.599934 7.599934 180)
			(size 0.4064 0.4064)
			(layers "F.Cu" "F.Mask" "F.Paste")
			(net "Net_66")
		)
		(pad "AC5" smd circle
			(at -6.800088 7.599934 180)
			(size 0.4064 0.4064)
			(layers "F.Cu" "F.Mask" "F.Paste")
			(net "Net_62")
		)
		(pad "AC6" smd circle
			(at -5.999988 7.599934 180)
			(size 0.4064 0.4064)
			(layers "F.Cu" "F.Mask" "F.Paste")
			(net "GND")
		)
		(pad "AC7" smd circle
			(at -5.199888 7.599934 180)
			(size 0.4064 0.4064)
			(layers "F.Cu" "F.Mask" "F.Paste")
			(net "ESPI_LPC_D3_IO3")
		)
		(pad "AC8" smd circle
			(at -4.400042 7.599934 180)
			(size 0.4064 0.4064)
			(layers "F.Cu" "F.Mask" "F.Paste")
			(net "ESPI_LPC_D2_IO2")
		)
		(pad "AC9" smd circle
			(at -3.599942 7.599934 180)
			(size 0.4064 0.4064)
			(layers "F.Cu" "F.Mask" "F.Paste")
			(net "IRQ_SMI_ACTIVE_BMC_N")
		)
		(pad "AC10" smd circle
			(at -2.800096 7.599934 180)
			(size 0.4064 0.4064)
			(layers "F.Cu" "F.Mask" "F.Paste")
			(net "SPI_BMC_TPM_CS2_R1_N")
		)
		(pad "AC11" smd circle
			(at -1.999996 7.599934 180)
			(size 0.4064 0.4064)
			(layers "F.Cu" "F.Mask" "F.Paste")
			(net "SPI_BMC_TPM_MOSI_R1")
		)
		(pad "AC12" smd circle
			(at -1.199896 7.599934 180)
			(size 0.4064 0.4064)
			(layers "F.Cu" "F.Mask" "F.Paste")
			(net "PU_BMC_FWSPIABR_N_R")
		)
		(pad "AC13" smd circle
			(at -0.40005 7.599934 180)
			(size 0.4064 0.4064)
			(layers "F.Cu" "F.Mask" "F.Paste")
			(net "TP_BMC_SPICS2_N")
		)
		(pad "AC14" smd circle
			(at 0.40005 7.599934 180)
			(size 0.4064 0.4064)
			(layers "F.Cu" "F.Mask" "F.Paste")
			(net "SPI_BMC_MOSI_IO0_R")
		)
		(pad "AC15" smd circle
			(at 1.199896 7.599934 180)
			(size 0.4064 0.4064)
			(layers "F.Cu" "F.Mask" "F.Paste")
			(net "FM_BMC_ONCTL_R_N")
		)
		(pad "AC16" smd circle
			(at 1.999996 7.599934 180)
			(size 0.4064 0.4064)
			(layers "F.Cu" "F.Mask" "F.Paste")
			(net "BSM_PRSNT_R_N")
		)
		(pad "AC17" smd circle
			(at 2.800096 7.599934 180)
			(size 0.4064 0.4064)
			(layers "F.Cu" "F.Mask" "F.Paste")
			(net "SMB_BMC_ALERT16_N")
		)
		(pad "AC18" smd circle
			(at 3.599942 7.599934 180)
			(size 0.4064 0.4064)
			(layers "F.Cu" "F.Mask" "F.Paste")
			(net "P5V_SENSOR")
		)
		(pad "AC19" smd circle
			(at 4.400042 7.599934 180)
			(size 0.4064 0.4064)
			(layers "F.Cu" "F.Mask" "F.Paste")
			(net "P1V8_SENSOR")
		)
		(pad "AC20" smd circle
			(at 5.199888 7.599934 180)
			(size 0.4064 0.4064)
			(layers "F.Cu" "F.Mask" "F.Paste")
			(net "A_BMC_ADCVREFP0")
		)
		(pad "AC21" smd circle
			(at 5.999988 7.599934 180)
			(size 0.4064 0.4064)
			(layers "F.Cu" "F.Mask" "F.Paste")
			(net "A_BMC_DACREST")
		)
		(pad "AC22" smd circle
			(at 6.800088 7.599934 180)
			(size 0.4064 0.4064)
			(layers "F.Cu" "F.Mask" "F.Paste")
			(net "FM_TPM_PRSNT_0_N")
		)
		(pad "AC23" smd circle
			(at 7.599934 7.599934 180)
			(size 0.4064 0.4064)
			(layers "F.Cu" "F.Mask" "F.Paste")
			(net "FM_SPD_REMOTE_EN_R")
		)
		(pad "AC24" smd circle
			(at 8.400034 7.599934 180)
			(size 0.4064 0.4064)
			(layers "F.Cu" "F.Mask" "F.Paste")
			(net "FM_ADR_COMPLETE")
		)
		(pad "AC25" smd circle
			(at 9.19988 7.599934 180)
			(size 0.4064 0.4064)
			(layers "F.Cu" "F.Mask" "F.Paste")
			(net "GND")
		)
		(pad "AC26" smd circle
			(at 9.99998 7.599934 180)
			(size 0.4064 0.4064)
			(layers "F.Cu" "F.Mask" "F.Paste")
			(net "FM_P12V_HSC_ENABLE_R1")
		)
		(pad "AD1" smd circle
			(at -9.99998 8.400034 180)
			(size 0.4064 0.4064)
			(layers "F.Cu" "F.Mask" "F.Paste")
			(net "GND")
		)
		(pad "AD2" smd circle
			(at -9.19988 8.400034 180)
			(size 0.4064 0.4064)
			(layers "F.Cu" "F.Mask" "F.Paste")
			(net "P2E_GPU_RX_DP")
		)
		(pad "AD3" smd circle
			(at -8.400034 8.400034 180)
			(size 0.4064 0.4064)
			(layers "F.Cu" "F.Mask" "F.Paste")
			(net "P2E_GPU_RX_DN")
		)
		(pad "AD4" smd circle
			(at -7.599934 8.400034 180)
			(size 0.4064 0.4064)
			(layers "F.Cu" "F.Mask" "F.Paste")
			(net "GND")
		)
		(pad "AD5" smd circle
			(at -6.800088 8.400034 180)
			(size 0.4064 0.4064)
			(layers "F.Cu" "F.Mask" "F.Paste")
			(net "CLK_100M_PCH_DP")
		)
		(pad "AD6" smd circle
			(at -5.999988 8.400034 180)
			(size 0.4064 0.4064)
			(layers "F.Cu" "F.Mask" "F.Paste")
			(net "CLK_100M_PCH_DN")
		)
	)
)
